# S9S_MB_2U (Grand Teton) — schematic netlist excerpt (pin names and nets, part order shuffled) for the footprints in the layout excerpt that follows; sources: Cadence DE-HDL packaged netlist, KiCad conversion of 03242023_DA0F0TMBIJ0_F0T_Motherboard_J_brd_V01_OCP.brd

R965  Q_RES  1K 1% CHIP  pkg 0402LF  page 235 : A = P3V3_AUX ; B = SMB_PEHPCPU0_LVC3_SCL
R3941  Q_RES  0 5% EMPTY  pkg 0402LF  page 250 : A = P12V_E1S_0_ISENSE_MAM_TIC ; B = P12V_E1S_0_ISENSE_TIC

(kicad_pcb
	(version 20260206)
	(generator "pcbnew")
	(generator_version "10.0")
	(general
		(thickness 1.6)
		(legacy_teardrops no)
	)
	(paper "A4")
	(title_block
		(title "03242023_DA0F0TMBIJ0_F0T_Motherboard_J_brd_V01_OCP.brd")
		(comment 1 "Grand Teton / footprints 5420-5421 of 6105")
	)
	(layers
		(0 "F.Cu" signal "TOP")
		(4 "In1.Cu" signal "GND")
		(6 "In2.Cu" signal "IN1")
		(8 "In3.Cu" signal "GND1")
		(10 "In4.Cu" signal "IN2")
		(12 "In5.Cu" signal "GND2")
		(14 "In6.Cu" signal "IN3")
		(16 "In7.Cu" signal "GND3")
		(18 "In8.Cu" signal "VCC")
		(20 "In9.Cu" signal "VCC1")
		(22 "In10.Cu" signal "GND4")
		(24 "In11.Cu" signal "IN4")
		(26 "In12.Cu" signal "GND5")
		(28 "In13.Cu" signal "IN5")
		(30 "In14.Cu" signal "GND6")
		(32 "In15.Cu" signal "IN6")
		(34 "In16.Cu" signal "GND7")
		(2 "B.Cu" signal "BOTTOM")
		(9 "F.Adhes" user "F.Adhesive")
		(11 "B.Adhes" user "B.Adhesive")
		(13 "F.Paste" user "Package Geometry/Pastemask Top")
		(15 "B.Paste" user "Package Geometry/Pastemask Bottom")
		(5 "F.SilkS" user "Ref Des/Silkscreen Top")
		(7 "B.SilkS" user "Ref Des/Silkscreen Bottom")
		(1 "F.Mask" user "Board Geometry/Soldermask Top")
		(3 "B.Mask" user "Board Geometry/Soldermask Bottom")
		(17 "Dwgs.User" user "User.Drawings")
		(19 "Cmts.User" user "User.Comments")
		(21 "Eco1.User" user "User.Eco1")
		(23 "Eco2.User" user "User.Eco2")
		(25 "Edge.Cuts" user "Board Geometry/Outline")
		(27 "Margin" user)
		(31 "F.CrtYd" user "Package Geometry/Place Bound Top")
		(29 "B.CrtYd" user "Package Geometry/Place Bound Bottom")
		(35 "F.Fab" user "Ref Des/Assembly Top")
		(33 "B.Fab" user "Ref Des/Assembly Bottom")
	)
	(footprint ""
		(layer "B.Cu")
		(at 369.117372 -184.400952 90)
		(property "Reference" "R965"
			(at 0 0 90)
			(layer "B.SilkS")
			(hide yes)
			(effects
				(font
					(size 1.27 1.27)
				)
				(justify mirror)
			)
		)
		(property "Value" ""
			(at 0 0 90)
			(layer "B.Fab")
			(effects
				(font
					(size 1.27 1.27)
				)
				(justify mirror)
			)
		)
		(duplicate_pad_numbers_are_jumpers no)
		(fp_line
			(start 0.7874 -0.4064)
			(end -0.7874 -0.4064)
			(stroke
				(width 0.1524)
				(type default)
			)
			(layer "B.SilkS")
		)
		(fp_line
			(start -0.7874 -0.4064)
			(end -0.7874 0.4064)
			(stroke
				(width 0.1524)
				(type default)
			)
			(layer "B.SilkS")
		)
		(fp_line
			(start 0.7874 0.4064)
			(end 0.7874 -0.4064)
			(stroke
				(width 0.1524)
				(type default)
			)
			(layer "B.SilkS")
		)
		(fp_line
			(start -0.7874 0.4064)
			(end 0.7874 0.4064)
			(stroke
				(width 0.1524)
				(type default)
			)
			(layer "B.SilkS")
		)
		(fp_line
			(start 0.67945 -0.305054)
			(end 0.12065 -0.305054)
			(stroke
				(width 0.1)
				(type default)
			)
			(layer "B.Fab")
		)
		(fp_line
			(start 0.12065 -0.305054)
			(end 0.12065 -0.2794)
			(stroke
				(width 0.1)
				(type default)
			)
			(layer "B.Fab")
		)
		(fp_line
			(start -0.12065 -0.3048)
			(end -0.67945 -0.3048)
			(stroke
				(width 0.1)
				(type default)
			)
			(layer "B.Fab")
		)
		(fp_line
			(start -0.67945 -0.3048)
			(end -0.67945 0.3048)
			(stroke
				(width 0.1)
				(type default)
			)
			(layer "B.Fab")
		)
		(fp_line
			(start 0.12065 -0.2794)
			(end -0.12065 -0.2794)
			(stroke
				(width 0.1)
				(type default)
			)
			(layer "B.Fab")
		)
		(fp_line
			(start -0.12065 -0.2794)
			(end -0.12065 -0.3048)
			(stroke
				(width 0.1)
				(type default)
			)
			(layer "B.Fab")
		)
		(fp_line
			(start 0.12065 0.2794)
			(end 0.12065 0.3048)
			(stroke
				(width 0.1)
				(type default)
			)
			(layer "B.Fab")
		)
		(fp_line
			(start -0.120396 0.2794)
			(end 0.12065 0.2794)
			(stroke
				(width 0.1)
				(type default)
			)
			(layer "B.Fab")
		)
		(fp_line
			(start 0.67945 0.3048)
			(end 0.67945 -0.305054)
			(stroke
				(width 0.1)
				(type default)
			)
			(layer "B.Fab")
		)
		(fp_line
			(start 0.12065 0.3048)
			(end 0.67945 0.3048)
			(stroke
				(width 0.1)
				(type default)
			)
			(layer "B.Fab")
		)
		(fp_line
			(start -0.120396 0.3048)
			(end -0.120396 0.2794)
			(stroke
				(width 0.1)
				(type default)
			)
			(layer "B.Fab")
		)
		(fp_line
			(start -0.67945 0.3048)
			(end -0.120396 0.3048)
			(stroke
				(width 0.1)
				(type default)
			)
			(layer "B.Fab")
		)
		(pad "1" smd circle
			(at 0.40005 0 270)
			(size 0 0)
			(layers "B.Cu" "B.Mask" "B.Paste")
			(net "P3V3_AUX")
		)
		(pad "2" smd circle
			(at -0.40005 0 270)
			(size 0 0)
			(layers "B.Cu" "B.Mask" "B.Paste")
			(net "SMB_PEHPCPU0_LVC3_SCL")
		)
	)
	(footprint ""
		(layer "B.Cu")
		(at 256.55397 -55.436262 180)
		(property "Reference" "R3941"
			(at 0 0 0)
			(layer "B.SilkS")
			(hide yes)
			(effects
				(font
					(size 1.27 1.27)
				)
				(justify mirror)
			)
		)
		(property "Value" ""
			(at 0 0 0)
			(layer "B.Fab")
			(effects
				(font
					(size 1.27 1.27)
				)
				(justify mirror)
			)
		)
		(duplicate_pad_numbers_are_jumpers no)
		(fp_line
			(start 0.7874 0.4064)
			(end 0.7874 -0.4064)
			(stroke
				(width 0.1524)
				(type default)
			)
			(layer "B.SilkS")
		)
		(fp_line
			(start 0.7874 -0.4064)
			(end -0.7874 -0.4064)
			(stroke
				(width 0.1524)
				(type default)
			)
			(layer "B.SilkS")
		)
		(fp_line
			(start -0.7874 0.4064)
			(end 0.7874 0.4064)
			(stroke
				(width 0.1524)
				(type default)
			)
			(layer "B.SilkS")
		)
		(fp_line
			(start -0.7874 -0.4064)
			(end -0.7874 0.4064)
			(stroke
				(width 0.1524)
				(type default)
			)
			(layer "B.SilkS")
		)
		(fp_line
			(start 0.67945 0.3048)
			(end 0.67945 -0.305054)
			(stroke
				(width 0.1)
				(type default)
			)
			(layer "B.Fab")
		)
		(fp_line
			(start 0.67945 -0.305054)
			(end 0.12065 -0.305054)
			(stroke
				(width 0.1)
				(type default)
			)
			(layer "B.Fab")
		)
		(fp_line
			(start 0.12065 0.3048)
			(end 0.67945 0.3048)
			(stroke
				(width 0.1)
				(type default)
			)
			(layer "B.Fab")
		)
		(fp_line
			(start 0.12065 0.2794)
			(end 0.12065 0.3048)
			(stroke
				(width 0.1)
				(type default)
			)
			(layer "B.Fab")
		)
		(fp_line
			(start 0.12065 -0.2794)
			(end -0.12065 -0.2794)
			(stroke
				(width 0.1)
				(type default)
			)
			(layer "B.Fab")
		)
		(fp_line
			(start 0.12065 -0.305054)
			(end 0.12065 -0.2794)
			(stroke
				(width 0.1)
				(type default)
			)
			(layer "B.Fab")
		)
		(fp_line
			(start -0.120396 0.3048)
			(end -0.120396 0.2794)
			(stroke
				(width 0.1)
				(type default)
			)
			(layer "B.Fab")
		)
		(fp_line
			(start -0.120396 0.2794)
			(end 0.12065 0.2794)
			(stroke
				(width 0.1)
				(type default)
			)
			(layer "B.Fab")
		)
		(fp_line
			(start -0.12065 -0.2794)
			(end -0.12065 -0.3048)
			(stroke
				(width 0.1)
				(type default)
			)
			(layer "B.Fab")
		)
		(fp_line
			(start -0.12065 -0.3048)
			(end -0.67945 -0.3048)
			(stroke
				(width 0.1)
				(type default)
			)
			(layer "B.Fab")
		)
		(fp_line
			(start -0.67945 0.3048)
			(end -0.120396 0.3048)
			(stroke
				(width 0.1)
				(type default)
			)
			(layer "B.Fab")
		)
		(fp_line
			(start -0.67945 -0.3048)
			(end -0.67945 0.3048)
			(stroke
				(width 0.1)
				(type default)
			)
			(layer "B.Fab")
		)
		(pad "1" smd rect
			(at 0.40005 0 180)
			(size 0.4572 0.508)
			(layers "B.Cu" "B.Mask" "B.Paste")
			(net "P12V_E1S_0_ISENSE_MAM_TIC")
		)
		(pad "2" smd rect
			(at -0.40005 0 180)
			(size 0.4572 0.508)
			(layers "B.Cu" "B.Mask" "B.Paste")
			(net "P12V_E1S_0_ISENSE_TIC")
		)
	)
)
